# TIMECARD (Time Appliance Project (Time Card)) — schematic netlist excerpt (pin names and nets, part order shuffled) for the footprints in the layout excerpt that follows; sources: Cadence DE-HDL packaged netlist, KiCad conversion of R4006-B0001-02_R01.brd

SP23  SOLDER_PREFORM  pkg 0201_SOLDER_PREFORM_4MIL  page 34 : \1\ = NC ; \2\ = NC
R373  RESISTOR  100OHM 1%  pkg SMC_0402R_H016  page 26 : \1\ = FPGA_OUT_SMA2_LED_RED_N ; \2\ = UNNAMED_14_LED4PV14_I266_3
R443  RESISTOR  100OHM 1%  pkg SMC_0402R_H016  page 24 : \1\ = FT_USB_DETECT ; \2\ = FPGA_IO_FT_USBDET_RST_N

(kicad_pcb
	(version 20260206)
	(generator "pcbnew")
	(generator_version "10.0")
	(general
		(thickness 1.6)
		(legacy_teardrops no)
	)
	(paper "A4")
	(title_block
		(title "timecard-production-celestica-r4006 — R4006-B0001-02_R01.brd")
		(comment 1 "Time Appliance Project (Time Card) / footprints 364-366 of 1113")
	)
	(layers
		(0 "F.Cu" signal "TOP")
		(4 "In1.Cu" signal "L02_GND1")
		(6 "In2.Cu" signal "L03_SIG1")
		(8 "In3.Cu" signal "L04_GND2")
		(10 "In4.Cu" signal "L05_VCC1")
		(12 "In5.Cu" signal "L06_VCC2")
		(14 "In6.Cu" signal "L07_GND3")
		(16 "In7.Cu" signal "L08_SIG2")
		(18 "In8.Cu" signal "L09_GND4")
		(2 "B.Cu" signal "BOTTOM")
		(9 "F.Adhes" user "F.Adhesive")
		(11 "B.Adhes" user "B.Adhesive")
		(13 "F.Paste" user "Package Geometry/Pastemask Top")
		(15 "B.Paste" user "Package Geometry/Pastemask Bottom")
		(5 "F.SilkS" user "Ref Des/Silkscreen Top")
		(7 "B.SilkS" user "Ref Des/Silkscreen Bottom")
		(1 "F.Mask" user "Board Geometry/Soldermask Top")
		(3 "B.Mask" user "Board Geometry/Soldermask Bottom")
		(17 "Dwgs.User" user "User.Drawings")
		(19 "Cmts.User" user "User.Comments")
		(21 "Eco1.User" user "User.Eco1")
		(23 "Eco2.User" user "User.Eco2")
		(25 "Edge.Cuts" user "Board Geometry/Outline")
		(27 "Margin" user)
		(31 "F.CrtYd" user "Package Geometry/Place Bound Top")
		(29 "B.CrtYd" user "Package Geometry/Place Bound Bottom")
		(35 "F.Fab" user "Ref Des/Assembly Top")
		(33 "B.Fab" user "Ref Des/Assembly Bottom")
	)
	(footprint ""
		(layer "F.Cu")
		(at 110.236 -88.265 -90)
		(property "Reference" "R443"
			(at 2.794 -0.16637 90)
			(unlocked yes)
			(layer "F.SilkS")
			(effects
				(font
					(size 0.7874 0.5842)
					(thickness 0.1524)
				)
			)
		)
		(property "Value" "VAL*"
			(at 0.02032 2.13233 270)
			(unlocked yes)
			(layer "F.Fab")
			(hide yes)
			(effects
				(font
					(size 0.7874 0.5842)
					(thickness 0.1524)
				)
			)
		)
		(property "Tolerance" "TOL*"
			(at 0.044704 3.05435 270)
			(unlocked yes)
			(layer "Cmts.User")
			(hide yes)
			(effects
				(font
					(size 0.7874 0.5842)
					(thickness 0.1524)
				)
			)
		)
		(property "User Part Number" "PARTNUM*"
			(at 0.02032 4.024884 270)
			(unlocked yes)
			(layer "Cmts.User")
			(hide yes)
			(effects
				(font
					(size 0.7874 0.5842)
					(thickness 0.1524)
				)
			)
		)
		(property "Device Type" "RESISTOR-G155-11000-01,100OHM,A"
			(at 0.008382 1.210564 270)
			(unlocked yes)
			(layer "F.Fab")
			(hide yes)
			(effects
				(font
					(size 0.7874 0.5842)
					(thickness 0.1524)
				)
			)
		)
		(duplicate_pad_numbers_are_jumpers no)
		(fp_line
			(start -1.143 0.5588)
			(end 1.143 0.5588)
			(stroke
				(width 0.1)
				(type default)
			)
			(layer "F.SilkS")
		)
		(fp_line
			(start 1.143 0.5588)
			(end 1.143 -0.5588)
			(stroke
				(width 0.1)
				(type default)
			)
			(layer "F.SilkS")
		)
		(fp_line
			(start -1.143 -0.5588)
			(end -1.143 0.5588)
			(stroke
				(width 0.1)
				(type default)
			)
			(layer "F.SilkS")
		)
		(fp_line
			(start 1.143 -0.5588)
			(end -1.143 -0.5588)
			(stroke
				(width 0.1)
				(type default)
			)
			(layer "F.SilkS")
		)
		(fp_poly
			(pts
				(xy -1.143 0.5588) (xy 1.143 0.5588) (xy 1.143 -0.5588) (xy -1.143 -0.5588)
			)
			(stroke
				(width 0)
				(type default)
			)
			(fill no)
			(layer "F.CrtYd")
		)
		(fp_line
			(start -0.508 0.3048)
			(end 0.508 0.3048)
			(stroke
				(width 0.1)
				(type default)
			)
			(layer "F.Fab")
		)
		(fp_line
			(start 0.508 0.3048)
			(end 0.508 -0.3048)
			(stroke
				(width 0.1)
				(type default)
			)
			(layer "F.Fab")
		)
		(fp_line
			(start -0.508 -0.3048)
			(end -0.508 0.3048)
			(stroke
				(width 0.1)
				(type default)
			)
			(layer "F.Fab")
		)
		(fp_line
			(start 0.508 -0.3048)
			(end -0.508 -0.3048)
			(stroke
				(width 0.1)
				(type default)
			)
			(layer "F.Fab")
		)
		(pad "1" smd rect
			(at -0.5334 0 270)
			(size 0.7112 0.6096)
			(layers "F.Cu" "F.Mask" "F.Paste")
			(net "FT_USB_DETECT")
		)
		(pad "2" smd rect
			(at 0.5334 0 270)
			(size 0.7112 0.6096)
			(layers "F.Cu" "F.Mask" "F.Paste")
			(net "FPGA_IO_FT_USBDET_RST_N")
		)
		(zone
			(layer "F.Cu")
			(hatch none 0.5)
			(connect_pads
				(clearance 0)
			)
			(min_thickness 0.25)
			(keepout
				(tracks not_allowed)
				(vias allowed)
				(pads allowed)
				(copperpour not_allowed)
				(footprints allowed)
			)
			(placement
				(enabled no)
				(sheetname "")
			)
			(fill
				(thermal_gap 0.5)
				(thermal_bridge_width 0.5)
				(island_removal_mode 0)
			)
			(polygon
				(pts
					(xy 109.9312 -88.3412) (xy 109.9312 -88.1888) (xy 110.5408 -88.1888) (xy 110.5408 -88.3412)
				)
			)
		)
		(zone
			(layer "F.Cu")
			(hatch none 0.5)
			(connect_pads
				(clearance 0)
			)
			(min_thickness 0.25)
			(keepout
				(tracks allowed)
				(vias not_allowed)
				(pads allowed)
				(copperpour not_allowed)
				(footprints allowed)
			)
			(placement
				(enabled no)
				(sheetname "")
			)
			(fill
				(thermal_gap 0.5)
				(thermal_bridge_width 0.5)
				(island_removal_mode 0)
			)
			(polygon
				(pts
					(xy 109.9312 -88.3412) (xy 109.9312 -88.1888) (xy 110.5408 -88.1888) (xy 110.5408 -88.3412)
				)
			)
		)
	)
	(footprint ""
		(layer "F.Cu")
		(at 34.798 -129.667)
		(property "Reference" "SP23"
			(at 0 0 0)
			(layer "F.SilkS")
			(hide yes)
			(effects
				(font
					(size 1.27 1.27)
				)
			)
		)
		(property "Value" ""
			(at 0 0 0)
			(layer "F.Fab")
			(effects
				(font
					(size 1.27 1.27)
				)
			)
		)
		(duplicate_pad_numbers_are_jumpers no)
	)
	(footprint ""
		(layer "F.Cu")
		(at 20.32 -29.21 180)
		(property "Reference" "R373"
			(at -2.794 -0.54737 0)
			(unlocked yes)
			(layer "F.SilkS")
			(effects
				(font
					(size 0.7874 0.5842)
					(thickness 0.1524)
				)
			)
		)
		(property "Value" "VAL*"
			(at 0.02032 2.13233 180)
			(unlocked yes)
			(layer "F.Fab")
			(hide yes)
			(effects
				(font
					(size 0.7874 0.5842)
					(thickness 0.1524)
				)
			)
		)
		(property "Device Type" "RESISTOR-G155-11000-01,100OHM,A"
			(at 0.008382 1.210564 180)
			(unlocked yes)
			(layer "F.Fab")
			(hide yes)
			(effects
				(font
					(size 0.7874 0.5842)
					(thickness 0.1524)
				)
			)
		)
		(property "User Part Number" "PARTNUM*"
			(at 0.02032 4.024884 180)
			(unlocked yes)
			(layer "Cmts.User")
			(hide yes)
			(effects
				(font
					(size 0.7874 0.5842)
					(thickness 0.1524)
				)
			)
		)
		(property "Tolerance" "TOL*"
			(at 0.044704 3.05435 180)
			(unlocked yes)
			(layer "Cmts.User")
			(hide yes)
			(effects
				(font
					(size 0.7874 0.5842)
					(thickness 0.1524)
				)
			)
		)
		(duplicate_pad_numbers_are_jumpers no)
		(fp_line
			(start 1.143 0.5588)
			(end 1.143 -0.5588)
			(stroke
				(width 0.1)
				(type default)
			)
			(layer "F.SilkS")
		)
		(fp_line
			(start 1.143 -0.5588)
			(end -1.143 -0.5588)
			(stroke
				(width 0.1)
				(type default)
			)
			(layer "F.SilkS")
		)
		(fp_line
			(start -1.143 0.5588)
			(end 1.143 0.5588)
			(stroke
				(width 0.1)
				(type default)
			)
			(layer "F.SilkS")
		)
		(fp_line
			(start -1.143 -0.5588)
			(end -1.143 0.5588)
			(stroke
				(width 0.1)
				(type default)
			)
			(layer "F.SilkS")
		)
		(fp_poly
			(pts
				(xy -1.143 0.5588) (xy 1.143 0.5588) (xy 1.143 -0.5588) (xy -1.143 -0.5588)
			)
			(stroke
				(width 0)
				(type default)
			)
			(fill no)
			(layer "F.CrtYd")
		)
		(fp_line
			(start 0.508 0.3048)
			(end 0.508 -0.3048)
			(stroke
				(width 0.1)
				(type default)
			)
			(layer "F.Fab")
		)
		(fp_line
			(start 0.508 -0.3048)
			(end -0.508 -0.3048)
			(stroke
				(width 0.1)
				(type default)
			)
			(layer "F.Fab")
		)
		(fp_line
			(start -0.508 0.3048)
			(end 0.508 0.3048)
			(stroke
				(width 0.1)
				(type default)
			)
			(layer "F.Fab")
		)
		(fp_line
			(start -0.508 -0.3048)
			(end -0.508 0.3048)
			(stroke
				(width 0.1)
				(type default)
			)
			(layer "F.Fab")
		)
		(pad "1" smd rect
			(at -0.5334 0 180)
			(size 0.7112 0.6096)
			(layers "F.Cu" "F.Mask" "F.Paste")
			(net "FPGA_OUT_SMA2_LED_RED_N")
		)
		(pad "2" smd rect
			(at 0.5334 0 180)
			(size 0.7112 0.6096)
			(layers "F.Cu" "F.Mask" "F.Paste")
			(net "UNNAMED_14_LED4PV14_I266_3")
		)
		(zone
			(layer "F.Cu")
			(hatch none 0.5)
			(connect_pads
				(clearance 0)
			)
			(min_thickness 0.25)
			(keepout
				(tracks not_allowed)
				(vias allowed)
				(pads allowed)
				(copperpour not_allowed)
				(footprints allowed)
			)
			(placement
				(enabled no)
				(sheetname "")
			)
			(fill
				(thermal_gap 0.5)
				(thermal_bridge_width 0.5)
				(island_removal_mode 0)
			)
			(polygon
				(pts
					(xy 20.3962 -29.5148) (xy 20.2438 -29.5148) (xy 20.2438 -28.9052) (xy 20.3962 -28.9052)
				)
			)
		)
		(zone
			(layer "F.Cu")
			(hatch none 0.5)
			(connect_pads
				(clearance 0)
			)
			(min_thickness 0.25)
			(keepout
				(tracks allowed)
				(vias not_allowed)
				(pads allowed)
				(copperpour not_allowed)
				(footprints allowed)
			)
			(placement
				(enabled no)
				(sheetname "")
			)
			(fill
				(thermal_gap 0.5)
				(thermal_bridge_width 0.5)
				(island_removal_mode 0)
			)
			(polygon
				(pts
					(xy 20.3962 -29.5148) (xy 20.2438 -29.5148) (xy 20.2438 -28.9052) (xy 20.3962 -28.9052)
				)
			)
		)
	)
)
